(kicad_pcb
	(version 20260206)
	(generator "pcbnew")
	(generator_version "10.0")
	(general
		(thickness 1.6)
		(legacy_teardrops no)
	)
	(paper "A4")
	(title_block
		(title "03242023_DA0F0TMBIJ0_F0T_Motherboard_J_brd_V01_OCP.brd")
		(comment 1 "Grand Teton / footprints 1048-1054 of 6105")
	)
	(layers
		(0 "F.Cu" signal "TOP")
		(4 "In1.Cu" signal "GND")
		(6 "In2.Cu" signal "IN1")
		(8 "In3.Cu" signal "GND1")
		(10 "In4.Cu" signal "IN2")
		(12 "In5.Cu" signal "GND2")
		(14 "In6.Cu" signal "IN3")
		(16 "In7.Cu" signal "GND3")
		(18 "In8.Cu" signal "VCC")
		(20 "In9.Cu" signal "VCC1")
		(22 "In10.Cu" signal "GND4")
		(24 "In11.Cu" signal "IN4")
		(26 "In12.Cu" signal "GND5")
		(28 "In13.Cu" signal "IN5")
		(30 "In14.Cu" signal "GND6")
		(32 "In15.Cu" signal "IN6")
		(34 "In16.Cu" signal "GND7")
		(2 "B.Cu" signal "BOTTOM")
		(9 "F.Adhes" user "F.Adhesive")
		(11 "B.Adhes" user "B.Adhesive")
		(13 "F.Paste" user "Package Geometry/Pastemask Top")
		(15 "B.Paste" user "Package Geometry/Pastemask Bottom")
		(5 "F.SilkS" user "Ref Des/Silkscreen Top")
		(7 "B.SilkS" user "Ref Des/Silkscreen Bottom")
		(1 "F.Mask" user "Board Geometry/Soldermask Top")
		(3 "B.Mask" user "Board Geometry/Soldermask Bottom")
		(17 "Dwgs.User" user "User.Drawings")
		(19 "Cmts.User" user "User.Comments")
		(21 "Eco1.User" user "User.Eco1")
		(23 "Eco2.User" user "User.Eco2")
		(25 "Edge.Cuts" user "Board Geometry/Outline")
		(27 "Margin" user)
		(31 "F.CrtYd" user "Package Geometry/Place Bound Top")
		(29 "B.CrtYd" user "Package Geometry/Place Bound Bottom")
		(35 "F.Fab" user "Ref Des/Assembly Top")
		(33 "B.Fab" user "Ref Des/Assembly Bottom")
	)
	(footprint ""
		(layer "F.Cu")
		(at 359.71988 -296.05478 180)
		(property "Reference" "C218"
			(at 0 0 180)
			(layer "F.SilkS")
			(hide yes)
			(effects
				(font
					(size 1.27 1.27)
				)
			)
		)
		(property "Value" ""
			(at 0 0 180)
			(layer "F.Fab")
			(effects
				(font
					(size 1.27 1.27)
				)
			)
		)
		(duplicate_pad_numbers_are_jumpers no)
		(fp_line
			(start 1.524 0.762)
			(end -1.524 0.762)
			(stroke
				(width 0.1524)
				(type default)
			)
			(layer "F.SilkS")
		)
		(fp_line
			(start 1.524 -0.762)
			(end 1.524 0.762)
			(stroke
				(width 0.1524)
				(type default)
			)
			(layer "F.SilkS")
		)
		(fp_line
			(start -1.524 0.762)
			(end -1.524 -0.762)
			(stroke
				(width 0.1524)
				(type default)
			)
			(layer "F.SilkS")
		)
		(fp_line
			(start -1.524 -0.762)
			(end 1.524 -0.762)
			(stroke
				(width 0.1524)
				(type default)
			)
			(layer "F.SilkS")
		)
		(fp_line
			(start 1.1049 0.724916)
			(end 1.1049 -0.724916)
			(stroke
				(width 0.1)
				(type default)
			)
			(layer "F.Fab")
		)
		(fp_line
			(start 1.1049 -0.724916)
			(end -1.1049 -0.724916)
			(stroke
				(width 0.1)
				(type default)
			)
			(layer "F.Fab")
		)
		(fp_line
			(start -1.1049 0.724916)
			(end 1.1049 0.724916)
			(stroke
				(width 0.1)
				(type default)
			)
			(layer "F.Fab")
		)
		(fp_line
			(start -1.1049 -0.724916)
			(end -1.1049 0.724916)
			(stroke
				(width 0.1)
				(type default)
			)
			(layer "F.Fab")
		)
		(pad "1" smd rect
			(at -0.889 0)
			(size 1.016 1.27)
			(layers "F.Cu" "F.Mask" "F.Paste")
			(net "PVCCIN_CPU0")
		)
		(pad "2" smd rect
			(at 0.889 0)
			(size 1.016 1.27)
			(layers "F.Cu" "F.Mask" "F.Paste")
			(net "GND")
		)
	)
	(footprint ""
		(layer "F.Cu")
		(at 31.8516 -69.7992 180)
		(property "Reference" "R4761"
			(at 0 0 180)
			(layer "F.SilkS")
			(hide yes)
			(effects
				(font
					(size 1.27 1.27)
				)
			)
		)
		(property "Value" ""
			(at 0 0 180)
			(layer "F.Fab")
			(effects
				(font
					(size 1.27 1.27)
				)
			)
		)
		(duplicate_pad_numbers_are_jumpers no)
		(fp_line
			(start 0.7874 0.4064)
			(end -0.7874 0.4064)
			(stroke
				(width 0.1524)
				(type default)
			)
			(layer "F.SilkS")
		)
		(fp_line
			(start 0.7874 -0.4064)
			(end 0.7874 0.4064)
			(stroke
				(width 0.1524)
				(type default)
			)
			(layer "F.SilkS")
		)
		(fp_line
			(start -0.7874 0.4064)
			(end -0.7874 -0.4064)
			(stroke
				(width 0.1524)
				(type default)
			)
			(layer "F.SilkS")
		)
		(fp_line
			(start -0.7874 -0.4064)
			(end 0.7874 -0.4064)
			(stroke
				(width 0.1524)
				(type default)
			)
			(layer "F.SilkS")
		)
		(fp_line
			(start 0.67945 0.3048)
			(end 0.120396 0.3048)
			(stroke
				(width 0.1)
				(type default)
			)
			(layer "F.Fab")
		)
		(fp_line
			(start 0.67945 -0.3048)
			(end 0.67945 0.3048)
			(stroke
				(width 0.1)
				(type default)
			)
			(layer "F.Fab")
		)
		(fp_line
			(start 0.12065 -0.2794)
			(end 0.12065 -0.3048)
			(stroke
				(width 0.1)
				(type default)
			)
			(layer "F.Fab")
		)
		(fp_line
			(start 0.12065 -0.3048)
			(end 0.67945 -0.3048)
			(stroke
				(width 0.1)
				(type default)
			)
			(layer "F.Fab")
		)
		(fp_line
			(start 0.120396 0.3048)
			(end 0.120396 0.2794)
			(stroke
				(width 0.1)
				(type default)
			)
			(layer "F.Fab")
		)
		(fp_line
			(start 0.120396 0.2794)
			(end -0.12065 0.2794)
			(stroke
				(width 0.1)
				(type default)
			)
			(layer "F.Fab")
		)
		(fp_line
			(start -0.12065 0.3048)
			(end -0.67945 0.3048)
			(stroke
				(width 0.1)
				(type default)
			)
			(layer "F.Fab")
		)
		(fp_line
			(start -0.12065 0.2794)
			(end -0.12065 0.3048)
			(stroke
				(width 0.1)
				(type default)
			)
			(layer "F.Fab")
		)
		(fp_line
			(start -0.12065 -0.2794)
			(end 0.12065 -0.2794)
			(stroke
				(width 0.1)
				(type default)
			)
			(layer "F.Fab")
		)
		(fp_line
			(start -0.12065 -0.305054)
			(end -0.12065 -0.2794)
			(stroke
				(width 0.1)
				(type default)
			)
			(layer "F.Fab")
		)
		(fp_line
			(start -0.67945 0.3048)
			(end -0.67945 -0.305054)
			(stroke
				(width 0.1)
				(type default)
			)
			(layer "F.Fab")
		)
		(fp_line
			(start -0.67945 -0.305054)
			(end -0.12065 -0.305054)
			(stroke
				(width 0.1)
				(type default)
			)
			(layer "F.Fab")
		)
		(pad "1" smd circle
			(at -0.40005 0 180)
			(size 0 0)
			(layers "F.Cu" "F.Mask" "F.Paste")
			(net "P3V3_AUX")
		)
		(pad "2" smd circle
			(at 0.40005 0 180)
			(size 0 0)
			(layers "F.Cu" "F.Mask" "F.Paste")
			(net "HP_LVC3_OCP_V3_2_PRSNT2_PLD_N")
		)
	)
	(footprint ""
		(layer "F.Cu")
		(at 66.94932 -56.540908 -90)
		(property "Reference" "PC2169"
			(at 0 0 270)
			(layer "F.SilkS")
			(hide yes)
			(effects
				(font
					(size 1.27 1.27)
				)
			)
		)
		(property "Value" ""
			(at 0 0 270)
			(layer "F.Fab")
			(effects
				(font
					(size 1.27 1.27)
				)
			)
		)
		(duplicate_pad_numbers_are_jumpers no)
		(fp_line
			(start -0.7874 0.4064)
			(end -0.7874 -0.4064)
			(stroke
				(width 0.1524)
				(type default)
			)
			(layer "F.SilkS")
		)
		(fp_line
			(start 0.7874 0.4064)
			(end -0.7874 0.4064)
			(stroke
				(width 0.1524)
				(type default)
			)
			(layer "F.SilkS")
		)
		(fp_line
			(start -0.7874 -0.4064)
			(end 0.7874 -0.4064)
			(stroke
				(width 0.1524)
				(type default)
			)
			(layer "F.SilkS")
		)
		(fp_line
			(start 0.7874 -0.4064)
			(end 0.7874 0.4064)
			(stroke
				(width 0.1524)
				(type default)
			)
			(layer "F.SilkS")
		)
		(fp_line
			(start -0.67945 0.3048)
			(end -0.67945 -0.305054)
			(stroke
				(width 0.1)
				(type default)
			)
			(layer "F.Fab")
		)
		(fp_line
			(start -0.12065 0.3048)
			(end -0.67945 0.3048)
			(stroke
				(width 0.1)
				(type default)
			)
			(layer "F.Fab")
		)
		(fp_line
			(start 0.120396 0.3048)
			(end 0.120396 0.2794)
			(stroke
				(width 0.1)
				(type default)
			)
			(layer "F.Fab")
		)
		(fp_line
			(start 0.67945 0.3048)
			(end 0.120396 0.3048)
			(stroke
				(width 0.1)
				(type default)
			)
			(layer "F.Fab")
		)
		(fp_line
			(start -0.12065 0.2794)
			(end -0.12065 0.3048)
			(stroke
				(width 0.1)
				(type default)
			)
			(layer "F.Fab")
		)
		(fp_line
			(start 0.120396 0.2794)
			(end -0.12065 0.2794)
			(stroke
				(width 0.1)
				(type default)
			)
			(layer "F.Fab")
		)
		(fp_line
			(start -0.12065 -0.2794)
			(end 0.12065 -0.2794)
			(stroke
				(width 0.1)
				(type default)
			)
			(layer "F.Fab")
		)
		(fp_line
			(start 0.12065 -0.2794)
			(end 0.12065 -0.3048)
			(stroke
				(width 0.1)
				(type default)
			)
			(layer "F.Fab")
		)
		(fp_line
			(start 0.12065 -0.3048)
			(end 0.67945 -0.3048)
			(stroke
				(width 0.1)
				(type default)
			)
			(layer "F.Fab")
		)
		(fp_line
			(start 0.67945 -0.3048)
			(end 0.67945 0.3048)
			(stroke
				(width 0.1)
				(type default)
			)
			(layer "F.Fab")
		)
		(fp_line
			(start -0.67945 -0.305054)
			(end -0.12065 -0.305054)
			(stroke
				(width 0.1)
				(type default)
			)
			(layer "F.Fab")
		)
		(fp_line
			(start -0.12065 -0.305054)
			(end -0.12065 -0.2794)
			(stroke
				(width 0.1)
				(type default)
			)
			(layer "F.Fab")
		)
		(pad "1" smd circle
			(at -0.40005 0 270)
			(size 0 0)
			(layers "F.Cu" "F.Mask" "F.Paste")
			(net "P3V3_AUX")
		)
		(pad "2" smd circle
			(at 0.40005 0 270)
			(size 0 0)
			(layers "F.Cu" "F.Mask" "F.Paste")
			(net "GND")
		)
	)
	(footprint ""
		(layer "F.Cu")
		(at 435.997858 -107.78236 180)
		(property "Reference" "PC5328"
			(at 0 0 180)
			(layer "F.SilkS")
			(hide yes)
			(effects
				(font
					(size 1.27 1.27)
				)
			)
		)
		(property "Value" ""
			(at 0 0 180)
			(layer "F.Fab")
			(effects
				(font
					(size 1.27 1.27)
				)
			)
		)
		(duplicate_pad_numbers_are_jumpers no)
		(fp_line
			(start 0.7874 0.4064)
			(end -0.7874 0.4064)
			(stroke
				(width 0.1524)
				(type default)
			)
			(layer "F.SilkS")
		)
		(fp_line
			(start 0.7874 -0.4064)
			(end 0.7874 0.4064)
			(stroke
				(width 0.1524)
				(type default)
			)
			(layer "F.SilkS")
		)
		(fp_line
			(start -0.7874 0.4064)
			(end -0.7874 -0.4064)
			(stroke
				(width 0.1524)
				(type default)
			)
			(layer "F.SilkS")
		)
		(fp_line
			(start -0.7874 -0.4064)
			(end 0.7874 -0.4064)
			(stroke
				(width 0.1524)
				(type default)
			)
			(layer "F.SilkS")
		)
		(fp_line
			(start 0.67945 0.3048)
			(end 0.120396 0.3048)
			(stroke
				(width 0.1)
				(type default)
			)
			(layer "F.Fab")
		)
		(fp_line
			(start 0.67945 -0.3048)
			(end 0.67945 0.3048)
			(stroke
				(width 0.1)
				(type default)
			)
			(layer "F.Fab")
		)
		(fp_line
			(start 0.12065 -0.2794)
			(end 0.12065 -0.3048)
			(stroke
				(width 0.1)
				(type default)
			)
			(layer "F.Fab")
		)
		(fp_line
			(start 0.12065 -0.3048)
			(end 0.67945 -0.3048)
			(stroke
				(width 0.1)
				(type default)
			)
			(layer "F.Fab")
		)
		(fp_line
			(start 0.120396 0.3048)
			(end 0.120396 0.2794)
			(stroke
				(width 0.1)
				(type default)
			)
			(layer "F.Fab")
		)
		(fp_line
			(start 0.120396 0.2794)
			(end -0.12065 0.2794)
			(stroke
				(width 0.1)
				(type default)
			)
			(layer "F.Fab")
		)
		(fp_line
			(start -0.12065 0.3048)
			(end -0.67945 0.3048)
			(stroke
				(width 0.1)
				(type default)
			)
			(layer "F.Fab")
		)
		(fp_line
			(start -0.12065 0.2794)
			(end -0.12065 0.3048)
			(stroke
				(width 0.1)
				(type default)
			)
			(layer "F.Fab")
		)
		(fp_line
			(start -0.12065 -0.2794)
			(end 0.12065 -0.2794)
			(stroke
				(width 0.1)
				(type default)
			)
			(layer "F.Fab")
		)
		(fp_line
			(start -0.12065 -0.305054)
			(end -0.12065 -0.2794)
			(stroke
				(width 0.1)
				(type default)
			)
			(layer "F.Fab")
		)
		(fp_line
			(start -0.67945 0.3048)
			(end -0.67945 -0.305054)
			(stroke
				(width 0.1)
				(type default)
			)
			(layer "F.Fab")
		)
		(fp_line
			(start -0.67945 -0.305054)
			(end -0.12065 -0.305054)
			(stroke
				(width 0.1)
				(type default)
			)
			(layer "F.Fab")
		)
		(pad "1" smd circle
			(at -0.40005 0 180)
			(size 0 0)
			(layers "F.Cu" "F.Mask" "F.Paste")
			(net "P3V3_AUX")
		)
		(pad "2" smd circle
			(at 0.40005 0 180)
			(size 0 0)
			(layers "F.Cu" "F.Mask" "F.Paste")
			(net "GND")
		)
	)
	(footprint ""
		(layer "F.Cu")
		(at 113.494312 -139.069826 180)
		(property "Reference" "R587"
			(at 0 0 180)
			(layer "F.SilkS")
			(hide yes)
			(effects
				(font
					(size 1.27 1.27)
				)
			)
		)
		(property "Value" ""
			(at 0 0 180)
			(layer "F.Fab")
			(effects
				(font
					(size 1.27 1.27)
				)
			)
		)
		(duplicate_pad_numbers_are_jumpers no)
		(fp_line
			(start 0.7874 0.4064)
			(end -0.7874 0.4064)
			(stroke
				(width 0.1524)
				(type default)
			)
			(layer "F.SilkS")
		)
		(fp_line
			(start 0.7874 -0.4064)
			(end 0.7874 0.4064)
			(stroke
				(width 0.1524)
				(type default)
			)
			(layer "F.SilkS")
		)
		(fp_line
			(start -0.7874 0.4064)
			(end -0.7874 -0.4064)
			(stroke
				(width 0.1524)
				(type default)
			)
			(layer "F.SilkS")
		)
		(fp_line
			(start -0.7874 -0.4064)
			(end 0.7874 -0.4064)
			(stroke
				(width 0.1524)
				(type default)
			)
			(layer "F.SilkS")
		)
		(fp_line
			(start 0.67945 0.3048)
			(end 0.120396 0.3048)
			(stroke
				(width 0.1)
				(type default)
			)
			(layer "F.Fab")
		)
		(fp_line
			(start 0.67945 -0.3048)
			(end 0.67945 0.3048)
			(stroke
				(width 0.1)
				(type default)
			)
			(layer "F.Fab")
		)
		(fp_line
			(start 0.12065 -0.2794)
			(end 0.12065 -0.3048)
			(stroke
				(width 0.1)
				(type default)
			)
			(layer "F.Fab")
		)
		(fp_line
			(start 0.12065 -0.3048)
			(end 0.67945 -0.3048)
			(stroke
				(width 0.1)
				(type default)
			)
			(layer "F.Fab")
		)
		(fp_line
			(start 0.120396 0.3048)
			(end 0.120396 0.2794)
			(stroke
				(width 0.1)
				(type default)
			)
			(layer "F.Fab")
		)
		(fp_line
			(start 0.120396 0.2794)
			(end -0.12065 0.2794)
			(stroke
				(width 0.1)
				(type default)
			)
			(layer "F.Fab")
		)
		(fp_line
			(start -0.12065 0.3048)
			(end -0.67945 0.3048)
			(stroke
				(width 0.1)
				(type default)
			)
			(layer "F.Fab")
		)
		(fp_line
			(start -0.12065 0.2794)
			(end -0.12065 0.3048)
			(stroke
				(width 0.1)
				(type default)
			)
			(layer "F.Fab")
		)
		(fp_line
			(start -0.12065 -0.2794)
			(end 0.12065 -0.2794)
			(stroke
				(width 0.1)
				(type default)
			)
			(layer "F.Fab")
		)
		(fp_line
			(start -0.12065 -0.305054)
			(end -0.12065 -0.2794)
			(stroke
				(width 0.1)
				(type default)
			)
			(layer "F.Fab")
		)
		(fp_line
			(start -0.67945 0.3048)
			(end -0.67945 -0.305054)
			(stroke
				(width 0.1)
				(type default)
			)
			(layer "F.Fab")
		)
		(fp_line
			(start -0.67945 -0.305054)
			(end -0.12065 -0.305054)
			(stroke
				(width 0.1)
				(type default)
			)
			(layer "F.Fab")
		)
		(pad "1" smd circle
			(at -0.40005 0 180)
			(size 0 0)
			(layers "F.Cu" "F.Mask" "F.Paste")
			(net "PCA9548_PCIE3_ADDR0")
		)
		(pad "2" smd circle
			(at 0.40005 0 180)
			(size 0 0)
			(layers "F.Cu" "F.Mask" "F.Paste")
			(net "GND")
		)
	)
	(footprint ""
		(layer "F.Cu")
		(at 69.923406 -148.228304)
		(property "Reference" "PC1593"
			(at 0 0 0)
			(layer "F.SilkS")
			(hide yes)
			(effects
				(font
					(size 1.27 1.27)
				)
			)
		)
		(property "Value" ""
			(at 0 0 0)
			(layer "F.Fab")
			(effects
				(font
					(size 1.27 1.27)
				)
			)
		)
		(duplicate_pad_numbers_are_jumpers no)
		(fp_line
			(start 2.750058 0.999998)
			(end -2.750058 0.999998)
			(stroke
				(width 0.1524)
				(type default)
			)
			(layer "F.SilkS")
		)
		(fp_circle
			(center 0 0.999998)
			(end 2.750058 0.999998)
			(stroke
				(width 0.1524)
				(type default)
			)
			(fill no)
			(layer "F.SilkS")
		)
		(fp_poly
			(pts
				(arc
					(start 2.750058 0.999998)
					(mid 0 3.750056)
					(end -2.750058 0.999998)
				)
			)
			(stroke
				(width 0)
				(type default)
			)
			(fill yes)
			(layer "F.SilkS")
		)
		(fp_circle
			(center 0 0.999998)
			(end 2.750058 0.999998)
			(stroke
				(width 0.1)
				(type default)
			)
			(fill no)
			(layer "F.Fab")
		)
		(pad "1" thru_hole rect
			(at 0 0)
			(size 1.5748 1.5748)
			(drill 1.0668)
			(layers "*.Cu" "*.Mask")
			(remove_unused_layers no)
			(net "PVCCINFAON_CPU1")
			(clearance 0)
			(padstack
				(mode front_inner_back)
				(layer "Inner"
					(shape circle)
					(size 1.5748 1.5748)
					(clearance 0)
				)
				(layer "B.Cu"
					(shape rect)
					(size 1.5748 1.5748)
					(clearance 0)
				)
			)
		)
		(pad "2" thru_hole circle
			(at 0 1.999996)
			(size 1.5748 1.5748)
			(drill 1.0668)
			(layers "*.Cu" "*.Mask")
			(remove_unused_layers no)
			(net "GND")
			(clearance 0)
		)
	)
	(footprint ""
		(layer "F.Cu")
		(at 22.460204 -384.978148 90)
		(property "Reference" "C2354"
			(at 0 0 90)
			(layer "F.SilkS")
			(hide yes)
			(effects
				(font
					(size 1.27 1.27)
				)
			)
		)
		(property "Value" ""
			(at 0 0 90)
			(layer "F.Fab")
			(effects
				(font
					(size 1.27 1.27)
				)
			)
		)
		(duplicate_pad_numbers_are_jumpers no)
		(fp_line
			(start 0.7874 -0.4064)
			(end 0.7874 0.4064)
			(stroke
				(width 0.1524)
				(type default)
			)
			(layer "F.SilkS")
		)
		(fp_line
			(start -0.7874 -0.4064)
			(end 0.7874 -0.4064)
			(stroke
				(width 0.1524)
				(type default)
			)
			(layer "F.SilkS")
		)
		(fp_line
			(start -0.005588 0.4064)
			(end -0.7874 0.4064)
			(stroke
				(width 0.1524)
				(type default)
			)
			(layer "F.SilkS")
		)
		(fp_line
			(start 0.6858 -0.3048)
			(end 0.6858 0.3048)
			(stroke
				(width 0.1)
				(type default)
			)
			(layer "F.Fab")
		)
		(fp_line
			(start 0.1016 -0.3048)
			(end 0.6858 -0.3048)
			(stroke
				(width 0.1)
				(type default)
			)
			(layer "F.Fab")
		)
		(fp_line
			(start -0.1016 -0.3048)
			(end -0.1016 -0.2794)
			(stroke
				(width 0.1)
				(type default)
			)
			(layer "F.Fab")
		)
		(fp_line
			(start -0.6858 -0.3048)
			(end -0.1016 -0.3048)
			(stroke
				(width 0.1)
				(type default)
			)
			(layer "F.Fab")
		)
		(fp_line
			(start 0.1016 -0.2794)
			(end 0.1016 -0.3048)
			(stroke
				(width 0.1)
				(type default)
			)
			(layer "F.Fab")
		)
		(fp_line
			(start -0.1016 -0.2794)
			(end 0.1016 -0.2794)
			(stroke
				(width 0.1)
				(type default)
			)
			(layer "F.Fab")
		)
		(fp_line
			(start 0.1016 0.2794)
			(end -0.1016 0.2794)
			(stroke
				(width 0.1)
				(type default)
			)
			(layer "F.Fab")
		)
		(fp_line
			(start -0.1016 0.2794)
			(end -0.1016 0.3048)
			(stroke
				(width 0.1)
				(type default)
			)
			(layer "F.Fab")
		)
		(fp_line
			(start 0.6858 0.3048)
			(end 0.1016 0.3048)
			(stroke
				(width 0.1)
				(type default)
			)
			(layer "F.Fab")
		)
		(fp_line
			(start 0.1016 0.3048)
			(end 0.1016 0.2794)
			(stroke
				(width 0.1)
				(type default)
			)
			(layer "F.Fab")
		)
		(fp_line
			(start -0.1016 0.3048)
			(end -0.6858 0.3048)
			(stroke
				(width 0.1)
				(type default)
			)
			(layer "F.Fab")
		)
		(fp_line
			(start -0.6858 0.3048)
			(end -0.6858 -0.3048)
			(stroke
				(width 0.1)
				(type default)
			)
			(layer "F.Fab")
		)
		(pad "1" smd rect
			(at -0.40005 0 270)
			(size 0.4572 0.508)
			(layers "F.Cu" "F.Mask" "F.Paste")
			(net "P2E_MB_BMC_RX_BUF2_C_DN<0>")
		)
		(pad "2" smd rect
			(at 0.40005 0 270)
			(size 0.4572 0.508)
			(layers "F.Cu" "F.Mask" "F.Paste")
			(net "P2E_MB_BMC_RX_BUF_DN<0>")
		)
	)
)
